FILE_TYPE = MACRO_DRAWING;
SET COLOR_WIRE YELLOW;
SET COLOR_PROP MONO;
SET COLOR_DOT WHITE;
SET COLOR_ARC YELLOW;
SET COLOR_BODY GREEN;
SET COLOR_NOTE MONO;
SET PROP_DISPLAY VALUE;
SET PAGE_NUMBER P8;
FORCEADD INTEL_CORP_BPAGE..1
(14550 100);
FORCEPROP 1 LAST CDS_CON_LAST_MODIFIED Fri Jun 16 17:47:59 2017
J 0
(13125 425);
PAINT ORANGE (13125 425);
DISPLAY INVISIBLE (13125 425);
FORCEPROP 1 LAST CUSTOM_TXT_CDS <CURRENT_DESIGN_SHEET> OF <TOTAL_DESIGN_SHEETS>
J 0
(14050 125);
PAINT ORANGE (14050 125);
FORCEPROP 1 LAST CUSTOM_TXT_CDS <CON_LAST_MODIFIED>
J 0
(10550 200);
PAINT ORANGE (10550 200);
FORCEPROP 2 LAST CUSTOM_TXT_CDS <XR_PAGE_TITLE>
J 0
(6660 5350);
DISPLAY 0.638298 (6660 5350);
PAINT PINK (6660 5350);
DISPLAY INVISIBLE (6660 5350);
FORCEPROP 1 LAST SCH_TITLE SMBUS BLOCK DIAGRAM
J 0
(6600 150);
DISPLAY 1.212766 (6600 150);
PAINT ORANGE (6600 150);
FORCEPROP 1 LAST COMMENT_BODY TRUE
J 0
(14562 112);
DISPLAY 0.468085 (14562 112);
PAINT GREEN (14562 112);
DISPLAY INVISIBLE (14562 112);
FORCEPROP 2 LAST PAGE_BORDER TRUE
J 0
(6660 5350);
DISPLAY 0.638298 (6660 5350);
PAINT PINK (6660 5350);
DISPLAY INVISIBLE (6660 5350);
FORCEPROP 2 LAST CDS_LIB mstr_symbols
J 0
(14550 100);
PAINT MONO (14550 100);
DISPLAY INVISIBLE (14550 100);
FORCEPROP 2 LAST CDS_XR_PAGE_TITLE CR-8 : @BASEBOARD_FAB2_LIB.BASEBOARD_FAB2(SCH_1):PAGE8
J 0
(6660 5350);
DISPLAY 0.638298 (6660 5350);
PAINT PINK (6660 5350);
DISPLAY INVISIBLE (6660 5350);
FORCENOTE
$CDS_IMAGE|SMBUS_Topology_NEW_20161028_1.jpg|5000|5000
(10600 2625) 0;
DISPLAY LEFT (10600 2625);
QUIT
